# T6G (Grand Teton) — schematic netlist excerpt (pin names and nets, part order shuffled) for the footprints in the layout excerpt that follows; sources: Cadence DE-HDL packaged netlist, KiCad conversion of 04192023_DAF0TMB3IC0_F0TG_MB_C_brd_V02_OCP.brd

D8006  SCHOTTKY_12  B0530WS7F EMPTY  pkg SOD323XB  page 104 : A = PWRGD_CHGL_CPU1_R1 ; C = P3V3_AUX
R1139  Q_RES  0 5% CHIP  pkg 0402LF  page 133 : A = CLK_50M_RMII ; B = CLK_50M_RMII_R

(kicad_pcb
	(version 20260206)
	(generator "pcbnew")
	(generator_version "10.0")
	(general
		(thickness 1.6)
		(legacy_teardrops no)
	)
	(paper "A4")
	(title_block
		(title "04192023_DAF0TMB3IC0_F0TG_MB_C_brd_V02_OCP.brd")
		(comment 1 "Grand Teton / footprints 2210-2211 of 8354")
	)
	(layers
		(0 "F.Cu" signal "TOP")
		(4 "In1.Cu" signal "GND")
		(6 "In2.Cu" signal "IN1")
		(8 "In3.Cu" signal "GND1")
		(10 "In4.Cu" signal "IN2")
		(12 "In5.Cu" signal "GND2")
		(14 "In6.Cu" signal "IN3")
		(16 "In7.Cu" signal "GND3")
		(18 "In8.Cu" signal "VCC")
		(20 "In9.Cu" signal "VCC1")
		(22 "In10.Cu" signal "GND4")
		(24 "In11.Cu" signal "IN4")
		(26 "In12.Cu" signal "GND5")
		(28 "In13.Cu" signal "IN5")
		(30 "In14.Cu" signal "GND6")
		(32 "In15.Cu" signal "IN6")
		(34 "In16.Cu" signal "GND7")
		(2 "B.Cu" signal "BOTTOM")
		(9 "F.Adhes" user "F.Adhesive")
		(11 "B.Adhes" user "B.Adhesive")
		(13 "F.Paste" user "Package Geometry/Pastemask Top")
		(15 "B.Paste" user "Package Geometry/Pastemask Bottom")
		(5 "F.SilkS" user "Ref Des/Silkscreen Top")
		(7 "B.SilkS" user "Ref Des/Silkscreen Bottom")
		(1 "F.Mask" user "Board Geometry/Soldermask Top")
		(3 "B.Mask" user "Board Geometry/Soldermask Bottom")
		(17 "Dwgs.User" user "User.Drawings")
		(19 "Cmts.User" user "User.Comments")
		(21 "Eco1.User" user "User.Eco1")
		(23 "Eco2.User" user "User.Eco2")
		(25 "Edge.Cuts" user "Board Geometry/Outline")
		(27 "Margin" user)
		(31 "F.CrtYd" user "Package Geometry/Place Bound Top")
		(29 "B.CrtYd" user "Package Geometry/Place Bound Bottom")
		(35 "F.Fab" user "Ref Des/Assembly Top")
		(33 "B.Fab" user "Ref Des/Assembly Bottom")
	)
	(footprint ""
		(layer "F.Cu")
		(at 201.676 -92.964)
		(property "Reference" "D8006"
			(at 4.037076 -0.588518 0)
			(unlocked yes)
			(layer "F.SilkS")
			(effects
				(font
					(size 0.7874 0.5842)
					(thickness 0.1524)
				)
				(justify left)
			)
		)
		(property "Value" ""
			(at 0 0 0)
			(layer "F.Fab")
			(effects
				(font
					(size 1.27 1.27)
				)
			)
		)
		(duplicate_pad_numbers_are_jumpers no)
		(fp_line
			(start -2.050796 -0.700024)
			(end 2.050796 -0.700024)
			(stroke
				(width 0.1524)
				(type default)
			)
			(layer "F.SilkS")
		)
		(fp_line
			(start -2.050796 0.700024)
			(end -2.050796 -0.700024)
			(stroke
				(width 0.1524)
				(type default)
			)
			(layer "F.SilkS")
		)
		(fp_line
			(start -0.30607 -0.500126)
			(end -0.30607 0.500126)
			(stroke
				(width 0.1524)
				(type default)
			)
			(layer "F.SilkS")
		)
		(fp_line
			(start -0.30607 0.500126)
			(end 0.193802 0)
			(stroke
				(width 0.1524)
				(type default)
			)
			(layer "F.SilkS")
		)
		(fp_line
			(start 0.193802 0)
			(end -0.30607 -0.500126)
			(stroke
				(width 0.1524)
				(type default)
			)
			(layer "F.SilkS")
		)
		(fp_line
			(start 0.293878 -0.500126)
			(end 0.293878 0.500126)
			(stroke
				(width 0.1524)
				(type default)
			)
			(layer "F.SilkS")
		)
		(fp_line
			(start 2.050796 -0.700024)
			(end 2.050796 0.700024)
			(stroke
				(width 0.1524)
				(type default)
			)
			(layer "F.SilkS")
		)
		(fp_line
			(start 2.050796 0.700024)
			(end -2.050796 0.700024)
			(stroke
				(width 0.1524)
				(type default)
			)
			(layer "F.SilkS")
		)
		(fp_line
			(start 2.051304 0.635)
			(end 2.152904 0.635)
			(stroke
				(width 0.1524)
				(type default)
			)
			(layer "F.SilkS")
		)
		(fp_line
			(start 2.051304 0.6985)
			(end 2.051304 0.635)
			(stroke
				(width 0.1524)
				(type default)
			)
			(layer "F.SilkS")
		)
		(fp_line
			(start 2.064004 -0.6985)
			(end 2.229104 -0.6985)
			(stroke
				(width 0.1524)
				(type default)
			)
			(layer "F.SilkS")
		)
		(fp_line
			(start 2.064004 -0.6731)
			(end 2.064004 -0.6985)
			(stroke
				(width 0.1524)
				(type default)
			)
			(layer "F.SilkS")
		)
		(fp_line
			(start 2.152904 -0.6985)
			(end 2.343404 -0.6985)
			(stroke
				(width 0.1524)
				(type default)
			)
			(layer "F.SilkS")
		)
		(fp_line
			(start 2.152904 0.635)
			(end 2.152904 -0.6985)
			(stroke
				(width 0.1524)
				(type default)
			)
			(layer "F.SilkS")
		)
		(fp_line
			(start 2.229104 -0.6985)
			(end 2.229104 0.6985)
			(stroke
				(width 0.1524)
				(type default)
			)
			(layer "F.SilkS")
		)
		(fp_line
			(start 2.229104 0.6985)
			(end 2.051304 0.6985)
			(stroke
				(width 0.1524)
				(type default)
			)
			(layer "F.SilkS")
		)
		(fp_line
			(start 2.343404 -0.6985)
			(end 2.343404 0.6985)
			(stroke
				(width 0.1524)
				(type default)
			)
			(layer "F.SilkS")
		)
		(fp_line
			(start 2.343404 0.6985)
			(end 2.216404 0.6985)
			(stroke
				(width 0.1524)
				(type default)
			)
			(layer "F.SilkS")
		)
		(fp_line
			(start -0.899922 -0.700024)
			(end 0.899922 -0.700024)
			(stroke
				(width 0.1)
				(type default)
			)
			(layer "F.Fab")
		)
		(fp_line
			(start -0.899922 0.700024)
			(end -0.899922 -0.700024)
			(stroke
				(width 0.1)
				(type default)
			)
			(layer "F.Fab")
		)
		(fp_line
			(start 0.899922 -0.700024)
			(end 0.899922 0.700024)
			(stroke
				(width 0.1)
				(type default)
			)
			(layer "F.Fab")
		)
		(fp_line
			(start 0.899922 0.700024)
			(end -0.899922 0.700024)
			(stroke
				(width 0.1)
				(type default)
			)
			(layer "F.Fab")
		)
		(fp_text user "+"
			(at -2.066544 -0.757682 90)
			(unlocked yes)
			(layer "F.SilkS")
			(effects
				(font
					(size 1.905 1.4224)
					(thickness 0.1524)
				)
				(justify left)
			)
		)
		(fp_text user "-"
			(at 3.880104 0.23495 180)
			(unlocked yes)
			(layer "F.SilkS")
			(effects
				(font
					(size 1.905 1.4224)
					(thickness 0.1524)
				)
				(justify left)
			)
		)
		(fp_text user "+"
			(at -3.123946 0.762 90)
			(unlocked yes)
			(layer "F.Fab")
			(effects
				(font
					(size 1.905 1.4224)
					(thickness 0.1524)
				)
				(justify left)
			)
		)
		(fp_text user "-"
			(at 3.880104 0.23495 180)
			(unlocked yes)
			(layer "F.Fab")
			(effects
				(font
					(size 1.905 1.4224)
					(thickness 0.1524)
				)
				(justify left)
			)
		)
		(pad "1" smd rect
			(at -1.199896 0 270)
			(size 0.6604 1.3716)
			(layers "F.Cu" "F.Mask" "F.Paste")
			(net "PWRGD_CHGL_CPU1_R1")
		)
		(pad "2" smd rect
			(at 1.199896 0 90)
			(size 0.6604 1.3716)
			(layers "F.Cu" "F.Mask" "F.Paste")
			(net "P3V3_AUX")
		)
	)
	(footprint ""
		(layer "F.Cu")
		(at 215.904064 -23.304754 -90)
		(property "Reference" "R1139"
			(at 0 0 270)
			(layer "F.SilkS")
			(hide yes)
			(effects
				(font
					(size 1.27 1.27)
				)
			)
		)
		(property "Value" ""
			(at 0 0 270)
			(layer "F.Fab")
			(effects
				(font
					(size 1.27 1.27)
				)
			)
		)
		(duplicate_pad_numbers_are_jumpers no)
		(fp_line
			(start -0.7874 0.4064)
			(end -0.7874 -0.4064)
			(stroke
				(width 0.1524)
				(type default)
			)
			(layer "F.SilkS")
		)
		(fp_line
			(start 0.7874 0.4064)
			(end -0.7874 0.4064)
			(stroke
				(width 0.1524)
				(type default)
			)
			(layer "F.SilkS")
		)
		(fp_line
			(start -0.7874 -0.4064)
			(end 0.7874 -0.4064)
			(stroke
				(width 0.1524)
				(type default)
			)
			(layer "F.SilkS")
		)
		(fp_line
			(start 0.7874 -0.4064)
			(end 0.7874 0.4064)
			(stroke
				(width 0.1524)
				(type default)
			)
			(layer "F.SilkS")
		)
		(fp_line
			(start -0.67945 0.3048)
			(end -0.67945 -0.305054)
			(stroke
				(width 0.1)
				(type default)
			)
			(layer "F.Fab")
		)
		(fp_line
			(start -0.12065 0.3048)
			(end -0.67945 0.3048)
			(stroke
				(width 0.1)
				(type default)
			)
			(layer "F.Fab")
		)
		(fp_line
			(start 0.120396 0.3048)
			(end 0.120396 0.2794)
			(stroke
				(width 0.1)
				(type default)
			)
			(layer "F.Fab")
		)
		(fp_line
			(start 0.67945 0.3048)
			(end 0.120396 0.3048)
			(stroke
				(width 0.1)
				(type default)
			)
			(layer "F.Fab")
		)
		(fp_line
			(start -0.12065 0.2794)
			(end -0.12065 0.3048)
			(stroke
				(width 0.1)
				(type default)
			)
			(layer "F.Fab")
		)
		(fp_line
			(start 0.120396 0.2794)
			(end -0.12065 0.2794)
			(stroke
				(width 0.1)
				(type default)
			)
			(layer "F.Fab")
		)
		(fp_line
			(start -0.12065 -0.2794)
			(end 0.12065 -0.2794)
			(stroke
				(width 0.1)
				(type default)
			)
			(layer "F.Fab")
		)
		(fp_line
			(start 0.12065 -0.2794)
			(end 0.12065 -0.3048)
			(stroke
				(width 0.1)
				(type default)
			)
			(layer "F.Fab")
		)
		(fp_line
			(start 0.12065 -0.3048)
			(end 0.67945 -0.3048)
			(stroke
				(width 0.1)
				(type default)
			)
			(layer "F.Fab")
		)
		(fp_line
			(start 0.67945 -0.3048)
			(end 0.67945 0.3048)
			(stroke
				(width 0.1)
				(type default)
			)
			(layer "F.Fab")
		)
		(fp_line
			(start -0.67945 -0.305054)
			(end -0.12065 -0.305054)
			(stroke
				(width 0.1)
				(type default)
			)
			(layer "F.Fab")
		)
		(fp_line
			(start -0.12065 -0.305054)
			(end -0.12065 -0.2794)
			(stroke
				(width 0.1)
				(type default)
			)
			(layer "F.Fab")
		)
		(pad "1" smd circle
			(at -0.40005 0 270)
			(size 0 0)
			(layers "F.Cu" "F.Mask" "F.Paste")
			(net "CLK_50M_RMII")
		)
		(pad "2" smd circle
			(at 0.40005 0 270)
			(size 0 0)
			(layers "F.Cu" "F.Mask" "F.Paste")
			(net "CLK_50M_RMII_R")
		)
	)
)
